FILE_TYPE = CONNECTIVITY;
{Allegro Design Entry HDL 17.4-2019 S026 (4007227) 1/17/2022}
"PAGE_NUMBER" = 67;
0"NC";
1"PVDD11_S3_P0\g";
2"GND\g";
3"PVDD11_S3_P0\g";
4"GND\g";
5"GND\g";
6"GND\g";
7"PVDDCR_SOC_P0\g";
8"PVDDCR_SOC_P0\g";
9"GND\g";
10"PVDDCR_SOC_P0\g";
11"PVDDIO_P0\g";
12"GND\g";
13"GND\g";
14"PVDD18_S5_P0\g";
%"Q_CAP"
"1","(-10425,5850)","0","pure_quanta","I100";
;
LOCATION"C2154"
$SEC"1"
CDS_SEC"1"
MATERIAL"X6S"
TOLERANCE"20%"
VALUE"22UF"
VOLTAGE"4V"
PACK_TYPE"C0402"
CDS_LIB"pure_quanta"
PART_NUMBER"CH622KMEB02";
"B"
$PN"2"9;
"A"
$PN"1"8;
%"Q_CAP"
"1","(-9975,5050)","0","pure_quanta","I101";
;
LOCATION"C3894"
$SEC"1"
CDS_SEC"1"
MATERIAL"X6S"
TOLERANCE"20%"
VALUE"22UF"
VOLTAGE"4V"
PACK_TYPE"C0402"
CDS_LIB"pure_quanta"
PART_NUMBER"CH622KMEB02";
"B"
$PN"2"6;
"A"
$PN"1"10;
%"Q_CAP"
"1","(-9525,5050)","0","pure_quanta","I102";
;
LOCATION"C3895"
$SEC"1"
CDS_SEC"1"
MATERIAL"X6S"
TOLERANCE"20%"
VALUE"22UF"
VOLTAGE"4V"
PACK_TYPE"C0402"
CDS_LIB"pure_quanta"
PART_NUMBER"CH622KMEB02";
"B"
$PN"2"6;
"A"
$PN"1"10;
%"Q_CAP"
"1","(-9975,5850)","0","pure_quanta","I103";
;
LOCATION"C2157"
$SEC"1"
CDS_SEC"1"
MATERIAL"X6S"
TOLERANCE"20%"
VALUE"22UF"
VOLTAGE"4V"
PACK_TYPE"C0402"
CDS_LIB"pure_quanta"
PART_NUMBER"CH622KMEB02";
"B"
$PN"2"9;
"A"
$PN"1"8;
%"Q_CAP"
"1","(-9525,5850)","0","pure_quanta","I104";
;
LOCATION"C2159"
$SEC"1"
CDS_SEC"1"
MATERIAL"X6S"
TOLERANCE"20%"
VALUE"22UF"
VOLTAGE"4V"
PACK_TYPE"C0402"
CDS_LIB"pure_quanta"
PART_NUMBER"CH622KMEB02";
"B"
$PN"2"9;
"A"
$PN"1"8;
%"UNIVERSAL_GND"
"1","(-9125,4675)","0","pure_quanta_power","I105";
;
CDS_LIB"pure_quanta_power"
HDL_POWER"GND";
"A"6;
%"Q_CAP"
"1","(-9125,5050)","0","pure_quanta","I106";
;
LOCATION"C3896"
$SEC"1"
CDS_SEC"1"
MATERIAL"X6S"
TOLERANCE"20%"
VALUE"22UF"
VOLTAGE"4V"
PACK_TYPE"C0402"
CDS_LIB"pure_quanta"
PART_NUMBER"CH622KMEB02";
"B"
$PN"2"6;
"A"
$PN"1"10;
%"UNIVERSAL_GND"
"1","(-9125,5475)","0","pure_quanta_power","I107";
;
CDS_LIB"pure_quanta_power"
HDL_POWER"GND";
"A"9;
%"Q_CAP"
"1","(-9125,5850)","0","pure_quanta","I108";
;
LOCATION"C2161"
$SEC"1"
CDS_SEC"1"
MATERIAL"X6S"
TOLERANCE"20%"
VALUE"22UF"
VOLTAGE"4V"
PACK_TYPE"C0402"
CDS_LIB"pure_quanta"
PART_NUMBER"CH622KMEB02";
"B"
$PN"2"9;
"A"
$PN"1"8;
%"Q_CAP"
"1","(-11325,5850)","0","pure_quanta","I109";
;
LOCATION"C2147"
$SEC"1"
CDS_SEC"1"
MATERIAL"X6S"
TOLERANCE"20%"
VALUE"22UF"
VOLTAGE"4V"
PACK_TYPE"C0402"
CDS_LIB"pure_quanta"
PART_NUMBER"CH622KMEB02";
"B"
$PN"2"9;
"A"
$PN"1"8;
%"Q_CAP"
"1","(-13125,1600)","0","pure_quanta","I110";
;
LOCATION"C2133"
$SEC"1"
CDS_SEC"1"
MATERIAL"X6S"
TOLERANCE"20%"
VALUE"22UF"
VOLTAGE"4V"
PACK_TYPE"C0402"
CDS_LIB"pure_quanta"
PART_NUMBER"CH622KMEB02";
"B"
$PN"2"2;
"A"
$PN"1"1;
%"UNIVERSAL_POWER"
"1","(-13125,1875)","0","pure_quanta_power","I111";
;
HDL_POWER"PVDD11_S3_P0"
CDS_LIB"pure_quanta_power";
"A"1;
%"Q_CAP"
"1","(-12675,1600)","0","pure_quanta","I112";
;
LOCATION"C2138"
$SEC"1"
CDS_SEC"1"
MATERIAL"X6S"
TOLERANCE"20%"
VALUE"22UF"
VOLTAGE"4V"
PACK_TYPE"C0402"
CDS_LIB"pure_quanta"
PART_NUMBER"CH622KMEB02";
"B"
$PN"2"2;
"A"
$PN"1"1;
%"Q_CAP"
"1","(-13125,2350)","0","pure_quanta","I113";
;
LOCATION"C2132"
$SEC"1"
CDS_SEC"1"
MATERIAL"X6S"
TOLERANCE"20%"
VALUE"22UF"
VOLTAGE"4V"
PACK_TYPE"C0402"
CDS_LIB"pure_quanta"
PART_NUMBER"CH622KMEB02";
"B"
$PN"2"4;
"A"
$PN"1"3;
%"UNIVERSAL_POWER"
"1","(-13125,2625)","0","pure_quanta_power","I114";
;
HDL_POWER"PVDD11_S3_P0"
CDS_LIB"pure_quanta_power";
"A"3;
%"Q_CAP"
"1","(-12675,2350)","0","pure_quanta","I115";
;
LOCATION"C2137"
$SEC"1"
CDS_SEC"1"
MATERIAL"X6S"
TOLERANCE"20%"
VALUE"22UF"
VOLTAGE"4V"
PACK_TYPE"C0402"
CDS_LIB"pure_quanta"
PART_NUMBER"CH622KMEB02";
"B"
$PN"2"4;
"A"
$PN"1"3;
%"Q_CAP"
"1","(-12225,1600)","0","pure_quanta","I116";
;
LOCATION"C3890"
$SEC"1"
CDS_SEC"1"
MATERIAL"X6S"
TOLERANCE"20%"
VALUE"22UF"
VOLTAGE"4V"
PACK_TYPE"C0402"
CDS_LIB"pure_quanta"
PART_NUMBER"CH622KMEB02";
"B"
$PN"2"2;
"A"
$PN"1"1;
%"Q_CAP"
"1","(-11775,1600)","0","pure_quanta","I117";
;
LOCATION"C3891"
$SEC"1"
CDS_SEC"1"
MATERIAL"X6S"
TOLERANCE"20%"
VALUE"22UF"
VOLTAGE"4V"
PACK_TYPE"C0402"
CDS_LIB"pure_quanta"
PART_NUMBER"CH622KMEB02";
"B"
$PN"2"2;
"A"
$PN"1"1;
%"Q_CAP"
"1","(-11325,1600)","0","pure_quanta","I118";
;
LOCATION"C3892"
$SEC"1"
CDS_SEC"1"
MATERIAL"X6S"
TOLERANCE"20%"
VALUE"22UF"
VOLTAGE"4V"
PACK_TYPE"C0402"
CDS_LIB"pure_quanta"
PART_NUMBER"CH622KMEB02";
"B"
$PN"2"2;
"A"
$PN"1"1;
%"UNIVERSAL_GND"
"1","(-10875,1225)","0","pure_quanta_power","I119";
;
CDS_LIB"pure_quanta_power"
HDL_POWER"GND";
"A"2;
%"Q_CAP"
"1","(-10875,1600)","0","pure_quanta","I120";
;
LOCATION"C3893"
$SEC"1"
CDS_SEC"1"
MATERIAL"X6S"
TOLERANCE"20%"
VALUE"22UF"
VOLTAGE"4V"
PACK_TYPE"C0402"
CDS_LIB"pure_quanta"
PART_NUMBER"CH622KMEB02";
"B"
$PN"2"2;
"A"
$PN"1"1;
%"Q_CAP"
"1","(-12225,2350)","0","pure_quanta","I121";
;
LOCATION"C2142"
$SEC"1"
CDS_SEC"1"
MATERIAL"X6S"
TOLERANCE"20%"
VALUE"22UF"
VOLTAGE"4V"
PACK_TYPE"C0402"
CDS_LIB"pure_quanta"
PART_NUMBER"CH622KMEB02";
"B"
$PN"2"4;
"A"
$PN"1"3;
%"Q_CAP"
"1","(-11775,2350)","0","pure_quanta","I122";
;
LOCATION"C2146"
$SEC"1"
CDS_SEC"1"
MATERIAL"X6S"
TOLERANCE"20%"
VALUE"22UF"
VOLTAGE"4V"
PACK_TYPE"C0402"
CDS_LIB"pure_quanta"
PART_NUMBER"CH622KMEB02";
"B"
$PN"2"4;
"A"
$PN"1"3;
%"Q_CAP"
"1","(-11325,2350)","0","pure_quanta","I123";
;
LOCATION"C2150"
$SEC"1"
CDS_SEC"1"
MATERIAL"X6S"
TOLERANCE"20%"
VALUE"22UF"
VOLTAGE"4V"
PACK_TYPE"C0402"
CDS_LIB"pure_quanta"
PART_NUMBER"CH622KMEB02";
"B"
$PN"2"4;
"A"
$PN"1"3;
%"Q_CAP"
"1","(-10875,2350)","0","pure_quanta","I124";
;
LOCATION"C2153"
$SEC"1"
CDS_SEC"1"
MATERIAL"X6S"
TOLERANCE"20%"
VALUE"22UF"
VOLTAGE"4V"
PACK_TYPE"C0402"
CDS_LIB"pure_quanta"
PART_NUMBER"CH622KMEB02";
"B"
$PN"2"4;
"A"
$PN"1"3;
%"Q_CAP"
"1","(-10425,2350)","0","pure_quanta","I125";
;
LOCATION"C2156"
$SEC"1"
CDS_SEC"1"
MATERIAL"X6S"
TOLERANCE"20%"
VALUE"22UF"
VOLTAGE"4V"
PACK_TYPE"C0402"
CDS_LIB"pure_quanta"
PART_NUMBER"CH622KMEB02";
"B"
$PN"2"4;
"A"
$PN"1"3;
%"UNIVERSAL_GND"
"1","(-9125,1975)","0","pure_quanta_power","I126";
;
CDS_LIB"pure_quanta_power"
HDL_POWER"GND";
"A"4;
%"Q_CAP"
"1","(-9975,2350)","0","pure_quanta","I127";
;
LOCATION"C2158"
$SEC"1"
CDS_SEC"1"
MATERIAL"X6S"
TOLERANCE"20%"
VALUE"22UF"
VOLTAGE"4V"
PACK_TYPE"C0402"
CDS_LIB"pure_quanta"
PART_NUMBER"CH622KMEB02";
"B"
$PN"2"4;
"A"
$PN"1"3;
%"Q_CAP"
"1","(-9525,2350)","0","pure_quanta","I128";
;
LOCATION"C2160"
$SEC"1"
CDS_SEC"1"
MATERIAL"X6S"
TOLERANCE"20%"
VALUE"22UF"
VOLTAGE"4V"
PACK_TYPE"C0402"
CDS_LIB"pure_quanta"
PART_NUMBER"CH622KMEB02";
"B"
$PN"2"4;
"A"
$PN"1"3;
%"Q_CAP"
"1","(-9125,2350)","0","pure_quanta","I129";
;
LOCATION"C2162"
$SEC"1"
CDS_SEC"1"
MATERIAL"X6S"
TOLERANCE"20%"
VALUE"22UF"
VOLTAGE"4V"
PACK_TYPE"C0402"
CDS_LIB"pure_quanta"
PART_NUMBER"CH622KMEB02";
"B"
$PN"2"4;
"A"
$PN"1"3;
%"UNIVERSAL_GND"
"1","(-7250,3850)","0","pure_quanta_power","I130";
;
CDS_LIB"pure_quanta_power"
HDL_POWER"GND";
"A"13;
%"Q_CAP"
"1","(-8150,4200)","0","pure_quanta","I131";
;
LOCATION"C2163"
$SEC"1"
CDS_SEC"1"
MATERIAL"X6S"
TOLERANCE"20%"
VALUE"22UF"
VOLTAGE"4V"
PACK_TYPE"C0402"
CDS_LIB"pure_quanta"
PART_NUMBER"CH622KMEB02";
"B"
$PN"2"13;
"A"
$PN"1"14;
%"UNIVERSAL_POWER"
"1","(-8150,4475)","0","pure_quanta_power","I132";
;
HDL_POWER"PVDD18_S5_P0"
CDS_LIB"pure_quanta_power";
"A"14;
%"Q_CAP"
"1","(-7700,4200)","0","pure_quanta","I133";
;
LOCATION"C2164"
$SEC"1"
CDS_SEC"1"
MATERIAL"X6S"
TOLERANCE"20%"
VALUE"22UF"
VOLTAGE"4V"
PACK_TYPE"C0402"
CDS_LIB"pure_quanta"
PART_NUMBER"CH622KMEB02";
"B"
$PN"2"13;
"A"
$PN"1"14;
%"Q_CAP"
"1","(-7250,4200)","0","pure_quanta","I134";
;
LOCATION"C3897"
$SEC"1"
CDS_SEC"1"
MATERIAL"X6S"
TOLERANCE"20%"
VALUE"22UF"
VOLTAGE"4V"
PACK_TYPE"C0402"
CDS_LIB"pure_quanta"
PART_NUMBER"CH622KMEB02";
"B"
$PN"2"13;
"A"
$PN"1"14;
%"Q_CAP"
"1","(-8200,5950)","0","pure_quanta","I135";
;
LOCATION"C2131"
$SEC"1"
CDS_SEC"1"
MATERIAL"X6S"
TOLERANCE"20%"
VALUE"22UF"
VOLTAGE"4V"
PACK_TYPE"C0402"
CDS_LIB"pure_quanta"
PART_NUMBER"CH622KMEB02";
"B"
$PN"2"12;
"A"
$PN"1"11;
%"Q_CAP"
"1","(-7750,5950)","0","pure_quanta","I136";
;
LOCATION"C2136"
$SEC"1"
CDS_SEC"1"
MATERIAL"X6S"
TOLERANCE"20%"
VALUE"22UF"
VOLTAGE"4V"
PACK_TYPE"C0402"
CDS_LIB"pure_quanta"
PART_NUMBER"CH622KMEB02";
"B"
$PN"2"12;
"A"
$PN"1"11;
%"Q_CAP"
"1","(-7300,5950)","0","pure_quanta","I137";
;
LOCATION"C2141"
$SEC"1"
CDS_SEC"1"
MATERIAL"X6S"
TOLERANCE"20%"
VALUE"22UF"
VOLTAGE"4V"
PACK_TYPE"C0402"
CDS_LIB"pure_quanta"
PART_NUMBER"CH622KMEB02";
"B"
$PN"2"12;
"A"
$PN"1"11;
%"Q_CAP"
"1","(-6850,5950)","0","pure_quanta","I138";
;
LOCATION"C2145"
$SEC"1"
CDS_SEC"1"
MATERIAL"X6S"
TOLERANCE"20%"
VALUE"22UF"
VOLTAGE"4V"
PACK_TYPE"C0402"
CDS_LIB"pure_quanta"
PART_NUMBER"CH622KMEB02";
"B"
$PN"2"12;
"A"
$PN"1"11;
%"Q_CAP"
"1","(-6400,5950)","0","pure_quanta","I139";
;
LOCATION"C2149"
$SEC"1"
CDS_SEC"1"
MATERIAL"X6S"
TOLERANCE"20%"
VALUE"22UF"
VOLTAGE"4V"
PACK_TYPE"C0402"
CDS_LIB"pure_quanta"
PART_NUMBER"CH622KMEB02";
"B"
$PN"2"12;
"A"
$PN"1"11;
%"UNIVERSAL_POWER"
"1","(-8200,6225)","0","pure_quanta_power","I140";
;
HDL_POWER"PVDDIO_P0"
CDS_LIB"pure_quanta_power";
"A"11;
%"Q_CAP"
"1","(-5950,5950)","0","pure_quanta","I141";
;
LOCATION"C3898"
$SEC"1"
CDS_SEC"1"
MATERIAL"X6S"
TOLERANCE"20%"
VALUE"22UF"
VOLTAGE"4V"
PACK_TYPE"C0402"
CDS_LIB"pure_quanta"
PART_NUMBER"CH622KMEB02";
"B"
$PN"2"12;
"A"
$PN"1"11;
%"UNIVERSAL_GND"
"1","(-5500,5600)","0","pure_quanta_power","I142";
;
CDS_LIB"pure_quanta_power"
HDL_POWER"GND";
"A"12;
%"Q_CAP"
"1","(-5500,5950)","0","pure_quanta","I143";
;
LOCATION"C3899"
$SEC"1"
CDS_SEC"1"
MATERIAL"X6S"
TOLERANCE"20%"
VALUE"22UF"
VOLTAGE"4V"
PACK_TYPE"C0402"
CDS_LIB"pure_quanta"
PART_NUMBER"CH622KMEB02";
"B"
$PN"2"12;
"A"
$PN"1"11;
%"UNIVERSAL_GND"
"1","(-12700,3900)","0","pure_quanta_power","I82";
;
CDS_LIB"pure_quanta_power"
HDL_POWER"GND";
"A"5;
%"Q_CAP"
"1","(-13100,4275)","0","pure_quanta","I83";
;
LOCATION"C3888"
$SEC"1"
CDS_SEC"1"
MATERIAL"X6S"
TOLERANCE"20%"
VALUE"22UF"
VOLTAGE"4V"
PACK_TYPE"C0402"
CDS_LIB"pure_quanta"
PART_NUMBER"CH622KMEB02";
"B"
$PN"2"5;
"A"
$PN"1"7;
%"UNIVERSAL_POWER"
"1","(-13100,4550)","0","pure_quanta_power","I84";
;
HDL_POWER"PVDDCR_SOC_P0"
CDS_LIB"pure_quanta_power";
"A"7;
%"Q_CAP"
"1","(-13125,5050)","0","pure_quanta","I85";
;
LOCATION"C2130"
$SEC"1"
CDS_SEC"1"
MATERIAL"X6S"
TOLERANCE"20%"
VALUE"22UF"
VOLTAGE"4V"
PACK_TYPE"C0402"
CDS_LIB"pure_quanta"
PART_NUMBER"CH622KMEB02";
"B"
$PN"2"6;
"A"
$PN"1"10;
%"Q_CAP"
"1","(-12700,4275)","0","pure_quanta","I86";
;
LOCATION"C3889"
$SEC"1"
CDS_SEC"1"
MATERIAL"X6S"
TOLERANCE"20%"
VALUE"22UF"
VOLTAGE"4V"
PACK_TYPE"C0402"
CDS_LIB"pure_quanta"
PART_NUMBER"CH622KMEB02";
"B"
$PN"2"5;
"A"
$PN"1"7;
%"Q_CAP"
"1","(-12675,5050)","0","pure_quanta","I87";
;
LOCATION"C2135"
$SEC"1"
CDS_SEC"1"
MATERIAL"X6S"
TOLERANCE"20%"
VALUE"22UF"
VOLTAGE"4V"
PACK_TYPE"C0402"
CDS_LIB"pure_quanta"
PART_NUMBER"CH622KMEB02";
"B"
$PN"2"6;
"A"
$PN"1"10;
%"UNIVERSAL_POWER"
"1","(-13125,5325)","0","pure_quanta_power","I88";
;
HDL_POWER"PVDDCR_SOC_P0"
CDS_LIB"pure_quanta_power";
"A"10;
%"Q_CAP"
"1","(-13125,5850)","0","pure_quanta","I89";
;
LOCATION"C2129"
$SEC"1"
CDS_SEC"1"
MATERIAL"X6S"
TOLERANCE"20%"
VALUE"22UF"
VOLTAGE"4V"
PACK_TYPE"C0402"
CDS_LIB"pure_quanta"
PART_NUMBER"CH622KMEB02";
"B"
$PN"2"9;
"A"
$PN"1"8;
%"Q_CAP"
"1","(-12675,5850)","0","pure_quanta","I90";
;
LOCATION"C2134"
$SEC"1"
CDS_SEC"1"
MATERIAL"X6S"
TOLERANCE"20%"
VALUE"22UF"
VOLTAGE"4V"
PACK_TYPE"C0402"
CDS_LIB"pure_quanta"
PART_NUMBER"CH622KMEB02";
"B"
$PN"2"9;
"A"
$PN"1"8;
%"UNIVERSAL_POWER"
"1","(-13125,6125)","0","pure_quanta_power","I91";
;
HDL_POWER"PVDDCR_SOC_P0"
CDS_LIB"pure_quanta_power";
"A"8;
%"Q_CAP"
"1","(-12225,5050)","0","pure_quanta","I92";
;
LOCATION"C2140"
$SEC"1"
CDS_SEC"1"
MATERIAL"X6S"
TOLERANCE"20%"
VALUE"22UF"
VOLTAGE"4V"
PACK_TYPE"C0402"
CDS_LIB"pure_quanta"
PART_NUMBER"CH622KMEB02";
"B"
$PN"2"6;
"A"
$PN"1"10;
%"Q_CAP"
"1","(-11775,5050)","0","pure_quanta","I93";
;
LOCATION"C2144"
$SEC"1"
CDS_SEC"1"
MATERIAL"X6S"
TOLERANCE"20%"
VALUE"22UF"
VOLTAGE"4V"
PACK_TYPE"C0402"
CDS_LIB"pure_quanta"
PART_NUMBER"CH622KMEB02";
"B"
$PN"2"6;
"A"
$PN"1"10;
%"Q_CAP"
"1","(-11325,5050)","0","pure_quanta","I94";
;
LOCATION"C2148"
$SEC"1"
CDS_SEC"1"
MATERIAL"X6S"
TOLERANCE"20%"
VALUE"22UF"
VOLTAGE"4V"
PACK_TYPE"C0402"
CDS_LIB"pure_quanta"
PART_NUMBER"CH622KMEB02";
"B"
$PN"2"6;
"A"
$PN"1"10;
%"Q_CAP"
"1","(-12225,5850)","0","pure_quanta","I95";
;
LOCATION"C2139"
$SEC"1"
CDS_SEC"1"
MATERIAL"X6S"
TOLERANCE"20%"
VALUE"22UF"
VOLTAGE"4V"
PACK_TYPE"C0402"
CDS_LIB"pure_quanta"
PART_NUMBER"CH622KMEB02";
"B"
$PN"2"9;
"A"
$PN"1"8;
%"Q_CAP"
"1","(-11775,5850)","0","pure_quanta","I96";
;
LOCATION"C2143"
$SEC"1"
CDS_SEC"1"
MATERIAL"X6S"
TOLERANCE"20%"
VALUE"22UF"
VOLTAGE"4V"
PACK_TYPE"C0402"
CDS_LIB"pure_quanta"
PART_NUMBER"CH622KMEB02";
"B"
$PN"2"9;
"A"
$PN"1"8;
%"Q_CAP"
"1","(-10875,5050)","0","pure_quanta","I97";
;
LOCATION"C2152"
$SEC"1"
CDS_SEC"1"
MATERIAL"X6S"
TOLERANCE"20%"
VALUE"22UF"
VOLTAGE"4V"
PACK_TYPE"C0402"
CDS_LIB"pure_quanta"
PART_NUMBER"CH622KMEB02";
"B"
$PN"2"6;
"A"
$PN"1"10;
%"Q_CAP"
"1","(-10425,5050)","0","pure_quanta","I98";
;
LOCATION"C2155"
$SEC"1"
CDS_SEC"1"
MATERIAL"X6S"
TOLERANCE"20%"
VALUE"22UF"
VOLTAGE"4V"
PACK_TYPE"C0402"
CDS_LIB"pure_quanta"
PART_NUMBER"CH622KMEB02";
"B"
$PN"2"6;
"A"
$PN"1"10;
%"Q_CAP"
"1","(-10875,5850)","0","pure_quanta","I99";
;
LOCATION"C2151"
$SEC"1"
CDS_SEC"1"
MATERIAL"X6S"
TOLERANCE"20%"
VALUE"22UF"
VOLTAGE"4V"
PACK_TYPE"C0402"
CDS_LIB"pure_quanta"
PART_NUMBER"CH622KMEB02";
"B"
$PN"2"9;
"A"
$PN"1"8;
END.
